# SCM (Grand Teton) — schematic netlist excerpt (pin names and nets, part order shuffled) for the footprints in the layout excerpt that follows; sources: Cadence DE-HDL packaged netlist, KiCad conversion of 12092022_DA0F0TMDCD0_F0T_Management_Board_D_brd_V3_OCP.brd

R228  Q_RES  10K 1% EMPTY  pkg 0402LF  page 32 : A = GND ; B = JTAG_MB_TCK
C169  Q_CAP  0.01UF 50V 10% EMPTY  pkg C0402  page 20 : A = P1V2_AUX ; B = P0V6_DDR_VREF_AUX

(kicad_pcb
	(version 20260206)
	(generator "pcbnew")
	(generator_version "10.0")
	(general
		(thickness 1.6)
		(legacy_teardrops no)
	)
	(paper "A4")
	(title_block
		(title "12092022_DA0F0TMDCD0_F0T_Management_Board_D_brd_V3_OCP.brd")
		(comment 1 "Grand Teton / footprints 1080-1081 of 1440")
	)
	(layers
		(0 "F.Cu" signal "TOP")
		(4 "In1.Cu" signal "GND")
		(6 "In2.Cu" signal "IN1")
		(8 "In3.Cu" signal "GND1")
		(10 "In4.Cu" signal "IN2")
		(12 "In5.Cu" signal "VCC")
		(14 "In6.Cu" signal "VCC1")
		(16 "In7.Cu" signal "IN3")
		(18 "In8.Cu" signal "GND2")
		(20 "In9.Cu" signal "IN4")
		(22 "In10.Cu" signal "GND3")
		(2 "B.Cu" signal "BOTTOM")
		(9 "F.Adhes" user "F.Adhesive")
		(11 "B.Adhes" user "B.Adhesive")
		(13 "F.Paste" user "Package Geometry/Pastemask Top")
		(15 "B.Paste" user "Package Geometry/Pastemask Bottom")
		(5 "F.SilkS" user "Ref Des/Silkscreen Top")
		(7 "B.SilkS" user "Ref Des/Silkscreen Bottom")
		(1 "F.Mask" user "Board Geometry/Soldermask Top")
		(3 "B.Mask" user "Board Geometry/Soldermask Bottom")
		(17 "Dwgs.User" user "User.Drawings")
		(19 "Cmts.User" user "User.Comments")
		(21 "Eco1.User" user "User.Eco1")
		(23 "Eco2.User" user "User.Eco2")
		(25 "Edge.Cuts" user "Board Geometry/Outline")
		(27 "Margin" user)
		(31 "F.CrtYd" user "Package Geometry/Place Bound Top")
		(29 "B.CrtYd" user "Package Geometry/Place Bound Bottom")
		(35 "F.Fab" user "Ref Des/Assembly Top")
		(33 "B.Fab" user "Ref Des/Assembly Bottom")
	)
	(footprint ""
		(layer "B.Cu")
		(at 40.0304 -106.3752 -90)
		(property "Reference" "R228"
			(at 0 0 90)
			(layer "B.SilkS")
			(hide yes)
			(effects
				(font
					(size 1.27 1.27)
				)
				(justify mirror)
			)
		)
		(property "Value" ""
			(at 0 0 90)
			(layer "B.Fab")
			(effects
				(font
					(size 1.27 1.27)
				)
				(justify mirror)
			)
		)
		(duplicate_pad_numbers_are_jumpers no)
		(fp_line
			(start -0.7874 0.4064)
			(end 0.7874 0.4064)
			(stroke
				(width 0.1524)
				(type default)
			)
			(layer "B.SilkS")
		)
		(fp_line
			(start 0.7874 0.4064)
			(end 0.7874 -0.4064)
			(stroke
				(width 0.1524)
				(type default)
			)
			(layer "B.SilkS")
		)
		(fp_line
			(start -0.7874 -0.4064)
			(end -0.7874 0.4064)
			(stroke
				(width 0.1524)
				(type default)
			)
			(layer "B.SilkS")
		)
		(fp_line
			(start 0.7874 -0.4064)
			(end -0.7874 -0.4064)
			(stroke
				(width 0.1524)
				(type default)
			)
			(layer "B.SilkS")
		)
		(fp_line
			(start -0.67945 0.3048)
			(end -0.120396 0.3048)
			(stroke
				(width 0.1)
				(type default)
			)
			(layer "B.Fab")
		)
		(fp_line
			(start -0.120396 0.3048)
			(end -0.120396 0.2794)
			(stroke
				(width 0.1)
				(type default)
			)
			(layer "B.Fab")
		)
		(fp_line
			(start 0.12065 0.3048)
			(end 0.67945 0.3048)
			(stroke
				(width 0.1)
				(type default)
			)
			(layer "B.Fab")
		)
		(fp_line
			(start 0.67945 0.3048)
			(end 0.67945 -0.305054)
			(stroke
				(width 0.1)
				(type default)
			)
			(layer "B.Fab")
		)
		(fp_line
			(start -0.120396 0.2794)
			(end 0.12065 0.2794)
			(stroke
				(width 0.1)
				(type default)
			)
			(layer "B.Fab")
		)
		(fp_line
			(start 0.12065 0.2794)
			(end 0.12065 0.3048)
			(stroke
				(width 0.1)
				(type default)
			)
			(layer "B.Fab")
		)
		(fp_line
			(start -0.12065 -0.2794)
			(end -0.12065 -0.3048)
			(stroke
				(width 0.1)
				(type default)
			)
			(layer "B.Fab")
		)
		(fp_line
			(start 0.12065 -0.2794)
			(end -0.12065 -0.2794)
			(stroke
				(width 0.1)
				(type default)
			)
			(layer "B.Fab")
		)
		(fp_line
			(start -0.67945 -0.3048)
			(end -0.67945 0.3048)
			(stroke
				(width 0.1)
				(type default)
			)
			(layer "B.Fab")
		)
		(fp_line
			(start -0.12065 -0.3048)
			(end -0.67945 -0.3048)
			(stroke
				(width 0.1)
				(type default)
			)
			(layer "B.Fab")
		)
		(fp_line
			(start 0.12065 -0.305054)
			(end 0.12065 -0.2794)
			(stroke
				(width 0.1)
				(type default)
			)
			(layer "B.Fab")
		)
		(fp_line
			(start 0.67945 -0.305054)
			(end 0.12065 -0.305054)
			(stroke
				(width 0.1)
				(type default)
			)
			(layer "B.Fab")
		)
		(pad "1" smd circle
			(at 0.40005 0 90)
			(size 0 0)
			(layers "B.Cu" "B.Mask" "B.Paste")
			(net "GND")
		)
		(pad "2" smd circle
			(at -0.40005 0 90)
			(size 0 0)
			(layers "B.Cu" "B.Mask" "B.Paste")
			(net "JTAG_MB_TCK")
		)
	)
	(footprint ""
		(layer "B.Cu")
		(at 82.108294 -52.746656 180)
		(property "Reference" "C169"
			(at 0 0 0)
			(layer "B.SilkS")
			(hide yes)
			(effects
				(font
					(size 1.27 1.27)
				)
				(justify mirror)
			)
		)
		(property "Value" ""
			(at 0 0 0)
			(layer "B.Fab")
			(effects
				(font
					(size 1.27 1.27)
				)
				(justify mirror)
			)
		)
		(duplicate_pad_numbers_are_jumpers no)
		(fp_line
			(start 0.7874 0.4064)
			(end 0.7874 -0.4064)
			(stroke
				(width 0.1524)
				(type default)
			)
			(layer "B.SilkS")
		)
		(fp_line
			(start 0.7874 -0.4064)
			(end -0.7874 -0.4064)
			(stroke
				(width 0.1524)
				(type default)
			)
			(layer "B.SilkS")
		)
		(fp_line
			(start -0.7874 0.4064)
			(end 0.7874 0.4064)
			(stroke
				(width 0.1524)
				(type default)
			)
			(layer "B.SilkS")
		)
		(fp_line
			(start -0.7874 -0.4064)
			(end -0.7874 0.4064)
			(stroke
				(width 0.1524)
				(type default)
			)
			(layer "B.SilkS")
		)
		(fp_line
			(start 0.67945 0.3048)
			(end 0.67945 -0.305054)
			(stroke
				(width 0.1)
				(type default)
			)
			(layer "B.Fab")
		)
		(fp_line
			(start 0.67945 -0.305054)
			(end 0.12065 -0.305054)
			(stroke
				(width 0.1)
				(type default)
			)
			(layer "B.Fab")
		)
		(fp_line
			(start 0.12065 0.3048)
			(end 0.67945 0.3048)
			(stroke
				(width 0.1)
				(type default)
			)
			(layer "B.Fab")
		)
		(fp_line
			(start 0.12065 0.2794)
			(end 0.12065 0.3048)
			(stroke
				(width 0.1)
				(type default)
			)
			(layer "B.Fab")
		)
		(fp_line
			(start 0.12065 -0.2794)
			(end -0.12065 -0.2794)
			(stroke
				(width 0.1)
				(type default)
			)
			(layer "B.Fab")
		)
		(fp_line
			(start 0.12065 -0.305054)
			(end 0.12065 -0.2794)
			(stroke
				(width 0.1)
				(type default)
			)
			(layer "B.Fab")
		)
		(fp_line
			(start -0.120396 0.3048)
			(end -0.120396 0.2794)
			(stroke
				(width 0.1)
				(type default)
			)
			(layer "B.Fab")
		)
		(fp_line
			(start -0.120396 0.2794)
			(end 0.12065 0.2794)
			(stroke
				(width 0.1)
				(type default)
			)
			(layer "B.Fab")
		)
		(fp_line
			(start -0.12065 -0.2794)
			(end -0.12065 -0.3048)
			(stroke
				(width 0.1)
				(type default)
			)
			(layer "B.Fab")
		)
		(fp_line
			(start -0.12065 -0.3048)
			(end -0.67945 -0.3048)
			(stroke
				(width 0.1)
				(type default)
			)
			(layer "B.Fab")
		)
		(fp_line
			(start -0.67945 0.3048)
			(end -0.120396 0.3048)
			(stroke
				(width 0.1)
				(type default)
			)
			(layer "B.Fab")
		)
		(fp_line
			(start -0.67945 -0.3048)
			(end -0.67945 0.3048)
			(stroke
				(width 0.1)
				(type default)
			)
			(layer "B.Fab")
		)
		(pad "1" smd circle
			(at 0.40005 0)
			(size 0 0)
			(layers "B.Cu" "B.Mask" "B.Paste")
			(net "P1V2_AUX")
		)
		(pad "2" smd circle
			(at -0.40005 0)
			(size 0 0)
			(layers "B.Cu" "B.Mask" "B.Paste")
			(net "P0V6_DDR_VREF_AUX")
		)
	)
)
